# SCM (Grand Teton) — schematic netlist excerpt (pin names and nets, part order shuffled) for the footprints in the layout excerpt that follows; sources: Cadence DE-HDL packaged netlist, KiCad conversion of 12092022_DA0F0TMDCD0_F0T_Management_Board_D_brd_V3_OCP.brd

C238  Q_CAP  0.1UF 25V 10% EMPTY  pkg 0402  page 29 : A = USB3_FPNL_TXP ; B = USB3_01_TXP_C
C130  Q_CAP  0.1UF 25V 10% X7R  pkg 0402  page 17 : A = P1V8_STBY_DP_VCC18A ; B = GND

(kicad_pcb
	(version 20260206)
	(generator "pcbnew")
	(generator_version "10.0")
	(general
		(thickness 1.6)
		(legacy_teardrops no)
	)
	(paper "A4")
	(title_block
		(title "12092022_DA0F0TMDCD0_F0T_Management_Board_D_brd_V3_OCP.brd")
		(comment 1 "Grand Teton / footprints 1181-1182 of 1440")
	)
	(layers
		(0 "F.Cu" signal "TOP")
		(4 "In1.Cu" signal "GND")
		(6 "In2.Cu" signal "IN1")
		(8 "In3.Cu" signal "GND1")
		(10 "In4.Cu" signal "IN2")
		(12 "In5.Cu" signal "VCC")
		(14 "In6.Cu" signal "VCC1")
		(16 "In7.Cu" signal "IN3")
		(18 "In8.Cu" signal "GND2")
		(20 "In9.Cu" signal "IN4")
		(22 "In10.Cu" signal "GND3")
		(2 "B.Cu" signal "BOTTOM")
		(9 "F.Adhes" user "F.Adhesive")
		(11 "B.Adhes" user "B.Adhesive")
		(13 "F.Paste" user "Package Geometry/Pastemask Top")
		(15 "B.Paste" user "Package Geometry/Pastemask Bottom")
		(5 "F.SilkS" user "Ref Des/Silkscreen Top")
		(7 "B.SilkS" user "Ref Des/Silkscreen Bottom")
		(1 "F.Mask" user "Board Geometry/Soldermask Top")
		(3 "B.Mask" user "Board Geometry/Soldermask Bottom")
		(17 "Dwgs.User" user "User.Drawings")
		(19 "Cmts.User" user "User.Comments")
		(21 "Eco1.User" user "User.Eco1")
		(23 "Eco2.User" user "User.Eco2")
		(25 "Edge.Cuts" user "Board Geometry/Outline")
		(27 "Margin" user)
		(31 "F.CrtYd" user "Package Geometry/Place Bound Top")
		(29 "B.CrtYd" user "Package Geometry/Place Bound Bottom")
		(35 "F.Fab" user "Ref Des/Assembly Top")
		(33 "B.Fab" user "Ref Des/Assembly Bottom")
	)
	(footprint ""
		(layer "B.Cu")
		(at 59.706256 -54.416198 -90)
		(property "Reference" "C130"
			(at 0 0 90)
			(layer "B.SilkS")
			(hide yes)
			(effects
				(font
					(size 1.27 1.27)
				)
				(justify mirror)
			)
		)
		(property "Value" ""
			(at 0 0 90)
			(layer "B.Fab")
			(effects
				(font
					(size 1.27 1.27)
				)
				(justify mirror)
			)
		)
		(duplicate_pad_numbers_are_jumpers no)
		(fp_line
			(start -0.7874 0.4064)
			(end 0.7874 0.4064)
			(stroke
				(width 0.1524)
				(type default)
			)
			(layer "B.SilkS")
		)
		(fp_line
			(start 0.7874 0.4064)
			(end 0.7874 -0.4064)
			(stroke
				(width 0.1524)
				(type default)
			)
			(layer "B.SilkS")
		)
		(fp_line
			(start -0.7874 -0.4064)
			(end -0.7874 0.4064)
			(stroke
				(width 0.1524)
				(type default)
			)
			(layer "B.SilkS")
		)
		(fp_line
			(start 0.7874 -0.4064)
			(end -0.7874 -0.4064)
			(stroke
				(width 0.1524)
				(type default)
			)
			(layer "B.SilkS")
		)
		(fp_line
			(start -0.67945 0.3048)
			(end -0.120396 0.3048)
			(stroke
				(width 0.1)
				(type default)
			)
			(layer "B.Fab")
		)
		(fp_line
			(start -0.120396 0.3048)
			(end -0.120396 0.2794)
			(stroke
				(width 0.1)
				(type default)
			)
			(layer "B.Fab")
		)
		(fp_line
			(start 0.12065 0.3048)
			(end 0.67945 0.3048)
			(stroke
				(width 0.1)
				(type default)
			)
			(layer "B.Fab")
		)
		(fp_line
			(start 0.67945 0.3048)
			(end 0.67945 -0.305054)
			(stroke
				(width 0.1)
				(type default)
			)
			(layer "B.Fab")
		)
		(fp_line
			(start -0.120396 0.2794)
			(end 0.12065 0.2794)
			(stroke
				(width 0.1)
				(type default)
			)
			(layer "B.Fab")
		)
		(fp_line
			(start 0.12065 0.2794)
			(end 0.12065 0.3048)
			(stroke
				(width 0.1)
				(type default)
			)
			(layer "B.Fab")
		)
		(fp_line
			(start -0.12065 -0.2794)
			(end -0.12065 -0.3048)
			(stroke
				(width 0.1)
				(type default)
			)
			(layer "B.Fab")
		)
		(fp_line
			(start 0.12065 -0.2794)
			(end -0.12065 -0.2794)
			(stroke
				(width 0.1)
				(type default)
			)
			(layer "B.Fab")
		)
		(fp_line
			(start -0.67945 -0.3048)
			(end -0.67945 0.3048)
			(stroke
				(width 0.1)
				(type default)
			)
			(layer "B.Fab")
		)
		(fp_line
			(start -0.12065 -0.3048)
			(end -0.67945 -0.3048)
			(stroke
				(width 0.1)
				(type default)
			)
			(layer "B.Fab")
		)
		(fp_line
			(start 0.12065 -0.305054)
			(end 0.12065 -0.2794)
			(stroke
				(width 0.1)
				(type default)
			)
			(layer "B.Fab")
		)
		(fp_line
			(start 0.67945 -0.305054)
			(end 0.12065 -0.305054)
			(stroke
				(width 0.1)
				(type default)
			)
			(layer "B.Fab")
		)
		(pad "1" smd circle
			(at 0.40005 0 90)
			(size 0 0)
			(layers "B.Cu" "B.Mask" "B.Paste")
			(net "P1V8_STBY_DP_VCC18A")
		)
		(pad "2" smd circle
			(at -0.40005 0 90)
			(size 0 0)
			(layers "B.Cu" "B.Mask" "B.Paste")
			(net "GND")
		)
	)
	(footprint ""
		(layer "B.Cu")
		(at 46.355 -96.8248 90)
		(property "Reference" "C238"
			(at 0 0 90)
			(layer "B.SilkS")
			(hide yes)
			(effects
				(font
					(size 1.27 1.27)
				)
				(justify mirror)
			)
		)
		(property "Value" ""
			(at 0 0 90)
			(layer "B.Fab")
			(effects
				(font
					(size 1.27 1.27)
				)
				(justify mirror)
			)
		)
		(duplicate_pad_numbers_are_jumpers no)
		(fp_line
			(start 0.7874 -0.4064)
			(end -0.7874 -0.4064)
			(stroke
				(width 0.1524)
				(type default)
			)
			(layer "B.SilkS")
		)
		(fp_line
			(start -0.7874 -0.4064)
			(end -0.7874 0.4064)
			(stroke
				(width 0.1524)
				(type default)
			)
			(layer "B.SilkS")
		)
		(fp_line
			(start 0.7874 0.4064)
			(end 0.7874 -0.4064)
			(stroke
				(width 0.1524)
				(type default)
			)
			(layer "B.SilkS")
		)
		(fp_line
			(start -0.7874 0.4064)
			(end 0.7874 0.4064)
			(stroke
				(width 0.1524)
				(type default)
			)
			(layer "B.SilkS")
		)
		(fp_line
			(start 0.67945 -0.305054)
			(end 0.12065 -0.305054)
			(stroke
				(width 0.1)
				(type default)
			)
			(layer "B.Fab")
		)
		(fp_line
			(start 0.12065 -0.305054)
			(end 0.12065 -0.2794)
			(stroke
				(width 0.1)
				(type default)
			)
			(layer "B.Fab")
		)
		(fp_line
			(start -0.12065 -0.3048)
			(end -0.67945 -0.3048)
			(stroke
				(width 0.1)
				(type default)
			)
			(layer "B.Fab")
		)
		(fp_line
			(start -0.67945 -0.3048)
			(end -0.67945 0.3048)
			(stroke
				(width 0.1)
				(type default)
			)
			(layer "B.Fab")
		)
		(fp_line
			(start 0.12065 -0.2794)
			(end -0.12065 -0.2794)
			(stroke
				(width 0.1)
				(type default)
			)
			(layer "B.Fab")
		)
		(fp_line
			(start -0.12065 -0.2794)
			(end -0.12065 -0.3048)
			(stroke
				(width 0.1)
				(type default)
			)
			(layer "B.Fab")
		)
		(fp_line
			(start 0.12065 0.2794)
			(end 0.12065 0.3048)
			(stroke
				(width 0.1)
				(type default)
			)
			(layer "B.Fab")
		)
		(fp_line
			(start -0.120396 0.2794)
			(end 0.12065 0.2794)
			(stroke
				(width 0.1)
				(type default)
			)
			(layer "B.Fab")
		)
		(fp_line
			(start 0.67945 0.3048)
			(end 0.67945 -0.305054)
			(stroke
				(width 0.1)
				(type default)
			)
			(layer "B.Fab")
		)
		(fp_line
			(start 0.12065 0.3048)
			(end 0.67945 0.3048)
			(stroke
				(width 0.1)
				(type default)
			)
			(layer "B.Fab")
		)
		(fp_line
			(start -0.120396 0.3048)
			(end -0.120396 0.2794)
			(stroke
				(width 0.1)
				(type default)
			)
			(layer "B.Fab")
		)
		(fp_line
			(start -0.67945 0.3048)
			(end -0.120396 0.3048)
			(stroke
				(width 0.1)
				(type default)
			)
			(layer "B.Fab")
		)
		(pad "1" smd circle
			(at 0.40005 0 270)
			(size 0 0)
			(layers "B.Cu" "B.Mask" "B.Paste")
			(net "USB3_FPNL_TXP")
		)
		(pad "2" smd circle
			(at -0.40005 0 270)
			(size 0 0)
			(layers "B.Cu" "B.Mask" "B.Paste")
			(net "USB3_01_TXP_C")
		)
	)
)
